#ISCELL
  pure_quanta quanta_title_block_c *
  *
#ISCELL
  standard offpage *
  page149_i216
#ISCELL
  standard offpage *
  page149_i217
#ISCELL
  standard offpage *
  page149_i218
#ISCELL
  standard offpage *
  page149_i219
#ISCELL
  standard offpage *
  page149_i220
#ISCELL
  standard offpage *
  page149_i221
#ISCELL
  standard offpage *
  page149_i222
#ISCELL
  standard offpage *
  page149_i223
#ISCELL
  standard offpage *
  page149_i224
#ISCELL
  standard offpage *
  page149_i225
#ISCELL
  standard offpage *
  page149_i226
#ISCELL
  standard offpage *
  page149_i227
#ISCELL
  standard offpage *
  page149_i228
#ISCELL
  standard offpage *
  page149_i229
#ISCELL
  standard offpage *
  page149_i230
#ISCELL
  standard offpage *
  page149_i231
#ISCELL
  standard offpage *
  page149_i232
#ISCELL
  standard offpage *
  page149_i233
#ISCELL
  standard offpage *
  page149_i234
#ISCELL
  standard offpage *
  page149_i235
#ISCELL
  standard offpage *
  page149_i236
#ISCELL
  standard offpage *
  page149_i237
#ISCELL
  standard offpage *
  page149_i238
#ISCELL
  standard offpage *
  page149_i239
#ISCELL
  standard offpage *
  page149_i240
#ISCELL
  standard offpage *
  page149_i241
#ISCELL
  standard offpage *
  page149_i242
#ISCELL
  standard offpage *
  page149_i243
#ISCELL
  standard offpage *
  page149_i244
#ISCELL
  standard offpage *
  page149_i245
#ISCELL
  standard offpage *
  page149_i246
#ISCELL
  standard offpage *
  page149_i247
#ISCELL
  standard offpage *
  page149_i248
#ISCELL
  standard offpage *
  page149_i249
#ISCELL
  standard offpage *
  page149_i250
#ISCELL
  standard offpage *
  page149_i251
#ISCELL
  standard offpage *
  page149_i252
#ISCELL
  standard offpage *
  page149_i253
#ISCELL
  standard offpage *
  page149_i254
#ISCELL
  standard offpage *
  page149_i255
#ISCELL
  standard offpage *
  page149_i256
#ISCELL
  standard offpage *
  page149_i257
#ISCELL
  standard offpage *
  page149_i258
#ISCELL
  standard offpage *
  page149_i259
#ISCELL
  standard offpage *
  page149_i260
#ISCELL
  standard offpage *
  page149_i261
#ISCELL
  standard offpage *
  page149_i262
#ISCELL
  standard offpage *
  page149_i263
#ISCELL
  standard offpage *
  page149_i264
#ISCELL
  standard offpage *
  page149_i265
#ISCELL
  standard offpage *
  page149_i266
#ISCELL
  standard offpage *
  page149_i267
#ISCELL
  standard offpage *
  page149_i268
#ISCELL
  standard offpage *
  page149_i269
#ISCELL
  standard offpage *
  page149_i270
#ISCELL
  standard offpage *
  page149_i271
#ISCELL
  standard offpage *
  page149_i272
#ISCELL
  standard offpage *
  page149_i273
#ISCELL
  standard offpage *
  page149_i274
#ISCELL
  standard offpage *
  page149_i275
#ISCELL
  standard offpage *
  page149_i276
#ISCELL
  standard offpage *
  page149_i277
#ISCELL
  standard offpage *
  page149_i278
#ISCELL
  standard offpage *
  page149_i279
#ISCELL
  standard offpage *
  page149_i280
#ISCELL
  standard offpage *
  page149_i292
#ISCELL
  standard offpage *
  page149_i293
#ISCELL
  standard offpage *
  page149_i294
#ISCELL
  standard offpage *
  page149_i295
#ISCELL
  standard offpage *
  page149_i298
#ISCELL
  standard offpage *
  page149_i299
#ISCELL
  standard offpage *
  page149_i302
#ISCELL
  standard offpage *
  page149_i304
#ISCELL
  standard offpage *
  page149_i305
#ISCELL
  standard offpage *
  page149_i310
#ISCELL
  standard offpage *
  page149_i311
#ISCELL
  standard offpage *
  page149_i312
#ISCELL
  standard offpage *
  page149_i313
#ISCELL
  standard offpage *
  page149_i318
#ISCELL
  standard offpage *
  page149_i319
#ISCELL
  standard offpage *
  page149_i336
#ISCELL
  standard offpage *
  page149_i337
#ISCELL
  standard offpage *
  page149_i338
#ISCELL
  standard offpage *
  page149_i339
#ISCELL
  standard offpage *
  page149_i340
#ISCELL
  standard offpage *
  page149_i341
#ISCELL
  standard offpage *
  page149_i342
#ISCELL
  standard offpage *
  page149_i343
#ISCELL
  standard offpage *
  page149_i344
#ISCELL
  standard offpage *
  page149_i345
#ISCELL
  standard offpage *
  page149_i346
#ISCELL
  standard offpage *
  page149_i347
#ISCELL
  standard offpage *
  page149_i348
#ISCELL
  standard offpage *
  page149_i349
#ISCELL
  standard offpage *
  page149_i350
#ISCELL
  standard offpage *
  page149_i351
#ISCELL
  standard offpage *
  page149_i352
#ISCELL
  standard offpage *
  page149_i353
#CELL
  pure_quanta conn160_10131762101lf *
  page149_i75
#CELL
  pure_quanta conn160_10131762101lf *
  page149_i76
#ISCELL
  logical_power universal_gnd *
  page149_i77
#ISCELL
  logical_power universal_gnd *
  page149_i78
